G04*
G04 #@! TF.GenerationSoftware,Altium Limited,Altium Designer,23.6.0 (18)*
G04*
G04 Layer_Color=8388736*
%FSLAX44Y44*%
%MOMM*%
G71*
G04*
G04 #@! TF.SameCoordinates,B62FFF2A-40BB-47C2-B022-6C0D6E2DF31E*
G04*
G04*
G04 #@! TF.FilePolarity,Negative*
G04*
G01*
G75*
%ADD26R,0.5500X0.6000*%
G04:AMPARAMS|DCode=27|XSize=1.164mm|YSize=0.3358mm|CornerRadius=0.1679mm|HoleSize=0mm|Usage=FLASHONLY|Rotation=90.000|XOffset=0mm|YOffset=0mm|HoleType=Round|Shape=RoundedRectangle|*
%AMROUNDEDRECTD27*
21,1,1.1640,0.0000,0,0,90.0*
21,1,0.8281,0.3358,0,0,90.0*
1,1,0.3358,0.0000,0.4141*
1,1,0.3358,0.0000,-0.4141*
1,1,0.3358,0.0000,-0.4141*
1,1,0.3358,0.0000,0.4141*
%
%ADD27ROUNDEDRECTD27*%
%ADD28R,0.3358X1.1640*%
%ADD32R,0.5153X0.4725*%
%ADD35R,1.1546X1.7062*%
%ADD43R,0.6500X0.7000*%
%ADD44R,0.9000X0.9000*%
%ADD45R,0.6500X0.6500*%
%ADD46R,0.6500X0.6500*%
%ADD47R,1.0000X1.0500*%
%ADD48R,1.0500X2.2000*%
%ADD49R,0.4500X1.5500*%
%ADD50C,1.1000*%
%ADD51R,1.3700X0.6588*%
%ADD52R,0.7000X1.0000*%
%ADD53R,0.6000X0.7000*%
%ADD54R,0.9000X0.9000*%
%ADD55R,0.9001X1.8983*%
%ADD56R,0.6000X0.6000*%
%ADD57R,0.6000X0.6000*%
%ADD58R,0.7000X0.6000*%
%ADD59C,0.5064*%
%ADD60C,5.6000*%
D26*
X102000Y136750D02*
D03*
Y129250D02*
D03*
X117000Y136750D02*
D03*
Y129250D02*
D03*
D27*
X63000Y147701D02*
D03*
X69500Y132299D02*
D03*
D28*
X56500D02*
D03*
D32*
X39214Y360000D02*
D03*
X46786D02*
D03*
D35*
X185758Y96000D02*
D03*
X160242D02*
D03*
X185758Y119000D02*
D03*
X160242D02*
D03*
D43*
X31000Y137250D02*
D03*
Y128750D02*
D03*
X42000Y137250D02*
D03*
Y128750D02*
D03*
X38000Y73250D02*
D03*
Y64750D02*
D03*
X80000Y73250D02*
D03*
Y64750D02*
D03*
D44*
X85384Y138540D02*
D03*
Y153540D02*
D03*
D45*
X85523Y118856D02*
D03*
Y127856D02*
D03*
D46*
X124500Y106000D02*
D03*
X115500D02*
D03*
D47*
X34000Y383750D02*
D03*
D48*
X19250Y399000D02*
D03*
X48750D02*
D03*
D49*
X17500Y12750D02*
D03*
X22500D02*
D03*
X27500D02*
D03*
X32500D02*
D03*
X37500D02*
D03*
X42500D02*
D03*
X47500D02*
D03*
X52500D02*
D03*
X57500D02*
D03*
X62500D02*
D03*
X67500D02*
D03*
X72500D02*
D03*
X77500D02*
D03*
X82500D02*
D03*
X87500D02*
D03*
X92500D02*
D03*
X97500D02*
D03*
X102500D02*
D03*
X107500D02*
D03*
X112500D02*
D03*
X117500D02*
D03*
X122500D02*
D03*
X127500D02*
D03*
X132500D02*
D03*
X137500D02*
D03*
X142500D02*
D03*
X147500D02*
D03*
X152500D02*
D03*
X187500D02*
D03*
X192500D02*
D03*
X197500D02*
D03*
X202500D02*
D03*
X182500D02*
D03*
X177500D02*
D03*
D50*
X132000Y154000D02*
D03*
X177000Y323000D02*
D03*
X118000Y325000D02*
D03*
X150000Y327000D02*
D03*
X170000Y375000D02*
D03*
X201000Y301000D02*
D03*
X104000Y154000D02*
D03*
X118000D02*
D03*
X145000D02*
D03*
D51*
X121304Y346850D02*
D03*
Y365150D02*
D03*
X102000Y356000D02*
D03*
D52*
X59500Y344000D02*
D03*
X74500D02*
D03*
D53*
X170000Y340000D02*
D03*
X160000D02*
D03*
X95000Y324000D02*
D03*
X105000D02*
D03*
X160000Y360000D02*
D03*
X170000D02*
D03*
D54*
X127500Y88000D02*
D03*
X112500D02*
D03*
D55*
X113000Y299998D02*
D03*
X156993D02*
D03*
X167992D02*
D03*
X178990D02*
D03*
X123999D02*
D03*
X134997D02*
D03*
X145995D02*
D03*
X83003D02*
D03*
X50009D02*
D03*
X61007D02*
D03*
X72005D02*
D03*
X39010D02*
D03*
X72005Y178002D02*
D03*
X50009D02*
D03*
X39010D02*
D03*
X83003D02*
D03*
X61007D02*
D03*
X145995D02*
D03*
X134997D02*
D03*
X123999D02*
D03*
X178990D02*
D03*
X167992D02*
D03*
X156993D02*
D03*
X113000D02*
D03*
D56*
X70000Y360000D02*
D03*
X60000D02*
D03*
X179000Y160000D02*
D03*
X169000D02*
D03*
X179000Y148000D02*
D03*
X169000D02*
D03*
X179000Y136000D02*
D03*
X169000D02*
D03*
D57*
X39000Y348000D02*
D03*
Y338000D02*
D03*
D58*
X66000Y64000D02*
D03*
Y74000D02*
D03*
X52000Y64000D02*
D03*
Y74000D02*
D03*
X190000Y335000D02*
D03*
Y345000D02*
D03*
X141000Y361000D02*
D03*
Y351000D02*
D03*
D59*
X69468Y121045D02*
D03*
X40000Y114000D02*
D03*
X50000Y115000D02*
D03*
X39000Y147000D02*
D03*
X118000Y47000D02*
D03*
X200000Y78350D02*
D03*
X207794Y79007D02*
D03*
X203112Y61996D02*
D03*
X211343Y71000D02*
D03*
X212000Y61000D02*
D03*
X63000Y38000D02*
D03*
X193000Y37000D02*
D03*
X208000Y193000D02*
D03*
X205000Y239000D02*
D03*
X206000Y215000D02*
D03*
Y259000D02*
D03*
Y268000D02*
D03*
Y276000D02*
D03*
X213640Y410220D02*
D03*
X209830Y402600D02*
D03*
X213640Y394980D02*
D03*
X209830Y387360D02*
D03*
X206020Y410220D02*
D03*
X202210Y402600D02*
D03*
X206020Y394980D02*
D03*
X202210Y387360D02*
D03*
Y174000D02*
D03*
Y158760D02*
D03*
Y143520D02*
D03*
X198400Y410220D02*
D03*
X194590Y402600D02*
D03*
X198400Y394980D02*
D03*
X194590Y387360D02*
D03*
X190780Y410220D02*
D03*
X186970Y402600D02*
D03*
X190780Y394980D02*
D03*
X186970Y387360D02*
D03*
X183160Y410220D02*
D03*
X179350Y402600D02*
D03*
X183160Y394980D02*
D03*
X179350Y387360D02*
D03*
X175540Y410220D02*
D03*
X171730Y402600D02*
D03*
X175540Y394980D02*
D03*
X171730Y387360D02*
D03*
X167920Y410220D02*
D03*
X164110Y402600D02*
D03*
X167920Y394980D02*
D03*
X164110Y387360D02*
D03*
X160300Y410220D02*
D03*
X156490Y402600D02*
D03*
X160300Y394980D02*
D03*
X156490Y387360D02*
D03*
X152680Y410220D02*
D03*
X148870Y402600D02*
D03*
X152680Y394980D02*
D03*
X148870Y387360D02*
D03*
X145060Y410220D02*
D03*
X141250Y402600D02*
D03*
X145060Y394980D02*
D03*
X141250Y387360D02*
D03*
X137440Y394980D02*
D03*
X133630Y387360D02*
D03*
X126010D02*
D03*
X110770Y372120D02*
D03*
X106960Y379740D02*
D03*
X103150Y372120D02*
D03*
X106960Y364500D02*
D03*
X103150Y341640D02*
D03*
X95530Y387360D02*
D03*
X99340Y379740D02*
D03*
X95530Y372120D02*
D03*
X99340Y364500D02*
D03*
X95530Y341640D02*
D03*
Y311160D02*
D03*
Y295920D02*
D03*
Y280680D02*
D03*
X87910Y387360D02*
D03*
X91720Y379740D02*
D03*
X87910Y372120D02*
D03*
X91720Y364500D02*
D03*
X87910Y341640D02*
D03*
Y326400D02*
D03*
X91720Y303540D02*
D03*
Y288300D02*
D03*
X87910Y280680D02*
D03*
X91720Y273060D02*
D03*
X87910Y265440D02*
D03*
X80290Y402600D02*
D03*
X84100Y394980D02*
D03*
X80290Y387360D02*
D03*
X84100Y379740D02*
D03*
X80290Y372120D02*
D03*
X84100Y364500D02*
D03*
Y334020D02*
D03*
X80290Y326400D02*
D03*
Y280680D02*
D03*
X84100Y273060D02*
D03*
X80290Y265440D02*
D03*
X76480Y410220D02*
D03*
X72670Y402600D02*
D03*
X76480Y394980D02*
D03*
X72670Y387360D02*
D03*
X76480Y379740D02*
D03*
X72670Y372120D02*
D03*
X76480Y334020D02*
D03*
X72670Y326400D02*
D03*
X76480Y318780D02*
D03*
Y273060D02*
D03*
X72670Y265440D02*
D03*
X68860Y410220D02*
D03*
X65050Y402600D02*
D03*
X68860Y394980D02*
D03*
X65050Y387360D02*
D03*
X68860Y379740D02*
D03*
X65050Y372120D02*
D03*
X68860Y334020D02*
D03*
X65050Y326400D02*
D03*
X68860Y318780D02*
D03*
Y273060D02*
D03*
X65050Y265440D02*
D03*
X61240Y379740D02*
D03*
X57430Y372120D02*
D03*
X61240Y334020D02*
D03*
X57430Y326400D02*
D03*
Y280680D02*
D03*
X53620Y379740D02*
D03*
X49810Y372120D02*
D03*
Y280680D02*
D03*
X42190D02*
D03*
X46000Y273060D02*
D03*
X42190Y265440D02*
D03*
X38380Y410220D02*
D03*
X34570Y402600D02*
D03*
Y280680D02*
D03*
X38380Y273060D02*
D03*
X34570Y265440D02*
D03*
X30760Y410220D02*
D03*
X26950Y326400D02*
D03*
X30760Y318780D02*
D03*
X26950Y311160D02*
D03*
X30760Y303540D02*
D03*
X26950Y295920D02*
D03*
X30760Y288300D02*
D03*
X26950Y280680D02*
D03*
X30760Y273060D02*
D03*
X26950Y265440D02*
D03*
X19330Y372120D02*
D03*
X23140Y364500D02*
D03*
X19330Y356880D02*
D03*
X23140Y349260D02*
D03*
X19330Y341640D02*
D03*
X23140Y334020D02*
D03*
X19330Y326400D02*
D03*
X23140Y318780D02*
D03*
X19330Y311160D02*
D03*
X23140Y303540D02*
D03*
X19330Y295920D02*
D03*
X23140Y288300D02*
D03*
X19330Y280680D02*
D03*
X23140Y273060D02*
D03*
X19330Y265440D02*
D03*
Y250200D02*
D03*
Y234960D02*
D03*
Y219720D02*
D03*
Y204480D02*
D03*
Y189240D02*
D03*
Y174000D02*
D03*
Y158760D02*
D03*
Y143520D02*
D03*
Y128280D02*
D03*
Y113040D02*
D03*
Y97800D02*
D03*
Y82560D02*
D03*
Y67320D02*
D03*
X15520Y379740D02*
D03*
X11710Y372120D02*
D03*
X15520Y364500D02*
D03*
X11710Y356880D02*
D03*
X15520Y349260D02*
D03*
X11710Y341640D02*
D03*
X15520Y334020D02*
D03*
X11710Y326400D02*
D03*
X15520Y318780D02*
D03*
X11710Y311160D02*
D03*
X15520Y303540D02*
D03*
X11710Y295920D02*
D03*
X15520Y288300D02*
D03*
X11710Y280680D02*
D03*
X15520Y273060D02*
D03*
X11710Y265440D02*
D03*
X15520Y257820D02*
D03*
X11710Y250200D02*
D03*
X15520Y242580D02*
D03*
X11710Y234960D02*
D03*
X15520Y227340D02*
D03*
X11710Y219720D02*
D03*
X15520Y212100D02*
D03*
X11710Y204480D02*
D03*
X15520Y196860D02*
D03*
X11710Y189240D02*
D03*
X15520Y181620D02*
D03*
X11710Y174000D02*
D03*
X15520Y166380D02*
D03*
X11710Y158760D02*
D03*
X15520Y151140D02*
D03*
X11710Y143520D02*
D03*
X15520Y135900D02*
D03*
X11710Y128280D02*
D03*
X15520Y120660D02*
D03*
X11710Y113040D02*
D03*
X15520Y105420D02*
D03*
X11710Y97800D02*
D03*
X15520Y90180D02*
D03*
X11710Y82560D02*
D03*
X15520Y74940D02*
D03*
X11710Y67320D02*
D03*
X15520Y59700D02*
D03*
X32151Y339810D02*
D03*
X31576Y332800D02*
D03*
X35076Y326800D02*
D03*
X38651Y320417D02*
D03*
X43408Y314602D02*
D03*
X55998Y314097D02*
D03*
X54580Y320095D02*
D03*
X50238Y325800D02*
D03*
X47228Y332057D02*
D03*
X46887Y338234D02*
D03*
X46651Y344528D02*
D03*
X41962Y367714D02*
D03*
X39820Y373823D02*
D03*
X31485Y353188D02*
D03*
X30909Y359800D02*
D03*
X29145Y365800D02*
D03*
X33000Y393477D02*
D03*
X23000Y383750D02*
D03*
X24523Y377500D02*
D03*
X28054Y371915D02*
D03*
X31719Y347000D02*
D03*
X46267Y350969D02*
D03*
X43782Y379467D02*
D03*
X41000Y393477D02*
D03*
X9000Y395000D02*
D03*
Y408000D02*
D03*
X62000Y394000D02*
D03*
X73000Y38000D02*
D03*
X187096Y64000D02*
D03*
X181031D02*
D03*
X78000Y86000D02*
D03*
X132530Y319000D02*
D03*
X126466D02*
D03*
X112000Y77000D02*
D03*
X106000Y106000D02*
D03*
X117000Y121000D02*
D03*
X102000Y119000D02*
D03*
X125000Y136750D02*
D03*
X94000D02*
D03*
X38000Y84000D02*
D03*
X83000Y317000D02*
D03*
X159000Y322000D02*
D03*
X50000Y161000D02*
D03*
X190000Y354000D02*
D03*
X177000Y340000D02*
D03*
X181000Y375000D02*
D03*
X145000Y368000D02*
D03*
X135000D02*
D03*
X95000Y334000D02*
D03*
X79000Y360000D02*
D03*
X39010Y160198D02*
D03*
X64425Y314602D02*
D03*
X36000Y314802D02*
D03*
X199000Y90000D02*
D03*
Y101000D02*
D03*
X198000Y117000D02*
D03*
Y126000D02*
D03*
X188000Y136000D02*
D03*
Y148000D02*
D03*
Y160000D02*
D03*
X159000Y152000D02*
D03*
Y145500D02*
D03*
Y139375D02*
D03*
X176000Y44000D02*
D03*
X195873Y44688D02*
D03*
X196187Y51172D02*
D03*
X111000Y35000D02*
D03*
X204114Y40000D02*
D03*
X203458Y48255D02*
D03*
X211000Y40000D02*
D03*
Y47870D02*
D03*
X152000Y36000D02*
D03*
X137000D02*
D03*
X123000Y35000D02*
D03*
X93000Y34000D02*
D03*
X33000Y31000D02*
D03*
Y38000D02*
D03*
X32880Y45166D02*
D03*
X33000Y51645D02*
D03*
X15000Y50312D02*
D03*
X12791Y42000D02*
D03*
X6395Y41971D02*
D03*
X6826Y50312D02*
D03*
X80000Y49000D02*
D03*
X45000D02*
D03*
X56000Y45000D02*
D03*
D60*
X110000Y420000D02*
D03*
M02*
